# S9S_MB_2U (Grand Teton) — schematic netlist excerpt (pin names and nets, part order shuffled) for the footprints in the layout excerpt that follows; sources: Cadence DE-HDL packaged netlist, KiCad conversion of 03242023_DA0F0TMBIJ0_F0T_Motherboard_J_brd_V01_OCP.brd

PC311_P0_2  Q_CAP  22UF 4V 20% X6S  pkg C0805  page 267 : A = PVCCIN_CPU0 ; B = GND
C1133  Q_CAP  0.01UF 50V 10% X7R  pkg C0402  page 217 : A = P3V3_AUX_FPGA_VCCIO2 ; B = GND
PR1797  Q_RES  0 5% CHIP  pkg 0402LF  page 293 : A = PVCCINFAON_CPU1_VOS2 ; B = PVCCINFAON_CPU1

(kicad_pcb
	(version 20260206)
	(generator "pcbnew")
	(generator_version "10.0")
	(general
		(thickness 1.6)
		(legacy_teardrops no)
	)
	(paper "A4")
	(title_block
		(title "03242023_DA0F0TMBIJ0_F0T_Motherboard_J_brd_V01_OCP.brd")
		(comment 1 "Grand Teton / footprints 4164-4166 of 6105")
	)
	(layers
		(0 "F.Cu" signal "TOP")
		(4 "In1.Cu" signal "GND")
		(6 "In2.Cu" signal "IN1")
		(8 "In3.Cu" signal "GND1")
		(10 "In4.Cu" signal "IN2")
		(12 "In5.Cu" signal "GND2")
		(14 "In6.Cu" signal "IN3")
		(16 "In7.Cu" signal "GND3")
		(18 "In8.Cu" signal "VCC")
		(20 "In9.Cu" signal "VCC1")
		(22 "In10.Cu" signal "GND4")
		(24 "In11.Cu" signal "IN4")
		(26 "In12.Cu" signal "GND5")
		(28 "In13.Cu" signal "IN5")
		(30 "In14.Cu" signal "GND6")
		(32 "In15.Cu" signal "IN6")
		(34 "In16.Cu" signal "GND7")
		(2 "B.Cu" signal "BOTTOM")
		(9 "F.Adhes" user "F.Adhesive")
		(11 "B.Adhes" user "B.Adhesive")
		(13 "F.Paste" user "Package Geometry/Pastemask Top")
		(15 "B.Paste" user "Package Geometry/Pastemask Bottom")
		(5 "F.SilkS" user "Ref Des/Silkscreen Top")
		(7 "B.SilkS" user "Ref Des/Silkscreen Bottom")
		(1 "F.Mask" user "Board Geometry/Soldermask Top")
		(3 "B.Mask" user "Board Geometry/Soldermask Bottom")
		(17 "Dwgs.User" user "User.Drawings")
		(19 "Cmts.User" user "User.Comments")
		(21 "Eco1.User" user "User.Eco1")
		(23 "Eco2.User" user "User.Eco2")
		(25 "Edge.Cuts" user "Board Geometry/Outline")
		(27 "Margin" user)
		(31 "F.CrtYd" user "Package Geometry/Place Bound Top")
		(29 "B.CrtYd" user "Package Geometry/Place Bound Bottom")
		(35 "F.Fab" user "Ref Des/Assembly Top")
		(33 "B.Fab" user "Ref Des/Assembly Bottom")
	)
	(footprint ""
		(layer "B.Cu")
		(at 51.95316 -143.759428)
		(property "Reference" "PR1797"
			(at 0 0 0)
			(layer "B.SilkS")
			(hide yes)
			(effects
				(font
					(size 1.27 1.27)
				)
				(justify mirror)
			)
		)
		(property "Value" ""
			(at 0 0 0)
			(layer "B.Fab")
			(effects
				(font
					(size 1.27 1.27)
				)
				(justify mirror)
			)
		)
		(duplicate_pad_numbers_are_jumpers no)
		(fp_line
			(start -0.7874 -0.4064)
			(end -0.7874 0.4064)
			(stroke
				(width 0.1524)
				(type default)
			)
			(layer "B.SilkS")
		)
		(fp_line
			(start -0.7874 0.4064)
			(end 0.7874 0.4064)
			(stroke
				(width 0.1524)
				(type default)
			)
			(layer "B.SilkS")
		)
		(fp_line
			(start 0.7874 -0.4064)
			(end -0.7874 -0.4064)
			(stroke
				(width 0.1524)
				(type default)
			)
			(layer "B.SilkS")
		)
		(fp_line
			(start 0.7874 0.4064)
			(end 0.7874 -0.4064)
			(stroke
				(width 0.1524)
				(type default)
			)
			(layer "B.SilkS")
		)
		(fp_line
			(start -0.67945 -0.3048)
			(end -0.67945 0.3048)
			(stroke
				(width 0.1)
				(type default)
			)
			(layer "B.Fab")
		)
		(fp_line
			(start -0.67945 0.3048)
			(end -0.120396 0.3048)
			(stroke
				(width 0.1)
				(type default)
			)
			(layer "B.Fab")
		)
		(fp_line
			(start -0.12065 -0.3048)
			(end -0.67945 -0.3048)
			(stroke
				(width 0.1)
				(type default)
			)
			(layer "B.Fab")
		)
		(fp_line
			(start -0.12065 -0.2794)
			(end -0.12065 -0.3048)
			(stroke
				(width 0.1)
				(type default)
			)
			(layer "B.Fab")
		)
		(fp_line
			(start -0.120396 0.2794)
			(end 0.12065 0.2794)
			(stroke
				(width 0.1)
				(type default)
			)
			(layer "B.Fab")
		)
		(fp_line
			(start -0.120396 0.3048)
			(end -0.120396 0.2794)
			(stroke
				(width 0.1)
				(type default)
			)
			(layer "B.Fab")
		)
		(fp_line
			(start 0.12065 -0.305054)
			(end 0.12065 -0.2794)
			(stroke
				(width 0.1)
				(type default)
			)
			(layer "B.Fab")
		)
		(fp_line
			(start 0.12065 -0.2794)
			(end -0.12065 -0.2794)
			(stroke
				(width 0.1)
				(type default)
			)
			(layer "B.Fab")
		)
		(fp_line
			(start 0.12065 0.2794)
			(end 0.12065 0.3048)
			(stroke
				(width 0.1)
				(type default)
			)
			(layer "B.Fab")
		)
		(fp_line
			(start 0.12065 0.3048)
			(end 0.67945 0.3048)
			(stroke
				(width 0.1)
				(type default)
			)
			(layer "B.Fab")
		)
		(fp_line
			(start 0.67945 -0.305054)
			(end 0.12065 -0.305054)
			(stroke
				(width 0.1)
				(type default)
			)
			(layer "B.Fab")
		)
		(fp_line
			(start 0.67945 0.3048)
			(end 0.67945 -0.305054)
			(stroke
				(width 0.1)
				(type default)
			)
			(layer "B.Fab")
		)
		(pad "1" smd circle
			(at 0.40005 0 180)
			(size 0 0)
			(layers "B.Cu" "B.Mask" "B.Paste")
			(net "PVCCINFAON_CPU1_VOS2")
		)
		(pad "2" smd circle
			(at -0.40005 0 180)
			(size 0 0)
			(layers "B.Cu" "B.Mask" "B.Paste")
			(net "PVCCINFAON_CPU1")
		)
	)
	(footprint ""
		(layer "B.Cu")
		(at 348.929706 -324.873366 -90)
		(property "Reference" "PC311_P0_2"
			(at 0 0 90)
			(layer "B.SilkS")
			(hide yes)
			(effects
				(font
					(size 1.27 1.27)
				)
				(justify mirror)
			)
		)
		(property "Value" ""
			(at 0 0 90)
			(layer "B.Fab")
			(effects
				(font
					(size 1.27 1.27)
				)
				(justify mirror)
			)
		)
		(duplicate_pad_numbers_are_jumpers no)
		(fp_line
			(start -1.524 0.762)
			(end 1.524 0.762)
			(stroke
				(width 0.1524)
				(type default)
			)
			(layer "B.SilkS")
		)
		(fp_line
			(start 1.524 0.762)
			(end 1.524 -0.762)
			(stroke
				(width 0.1524)
				(type default)
			)
			(layer "B.SilkS")
		)
		(fp_line
			(start -1.524 -0.762)
			(end -1.524 0.762)
			(stroke
				(width 0.1524)
				(type default)
			)
			(layer "B.SilkS")
		)
		(fp_line
			(start 1.524 -0.762)
			(end -1.524 -0.762)
			(stroke
				(width 0.1524)
				(type default)
			)
			(layer "B.SilkS")
		)
		(fp_line
			(start -1.1049 0.724916)
			(end -1.1049 -0.724916)
			(stroke
				(width 0.1)
				(type default)
			)
			(layer "B.Fab")
		)
		(fp_line
			(start 1.1049 0.724916)
			(end -1.1049 0.724916)
			(stroke
				(width 0.1)
				(type default)
			)
			(layer "B.Fab")
		)
		(fp_line
			(start -1.1049 -0.724916)
			(end 1.1049 -0.724916)
			(stroke
				(width 0.1)
				(type default)
			)
			(layer "B.Fab")
		)
		(fp_line
			(start 1.1049 -0.724916)
			(end 1.1049 0.724916)
			(stroke
				(width 0.1)
				(type default)
			)
			(layer "B.Fab")
		)
		(pad "1" smd rect
			(at 0.889 0 270)
			(size 1.016 1.27)
			(layers "B.Cu" "B.Mask" "B.Paste")
			(net "PVCCIN_CPU0")
		)
		(pad "2" smd rect
			(at -0.889 0 270)
			(size 1.016 1.27)
			(layers "B.Cu" "B.Mask" "B.Paste")
			(net "GND")
		)
	)
	(footprint ""
		(layer "B.Cu")
		(at 181.755542 -115.375436)
		(property "Reference" "C1133"
			(at 0 0 0)
			(layer "B.SilkS")
			(hide yes)
			(effects
				(font
					(size 1.27 1.27)
				)
				(justify mirror)
			)
		)
		(property "Value" ""
			(at 0 0 0)
			(layer "B.Fab")
			(effects
				(font
					(size 1.27 1.27)
				)
				(justify mirror)
			)
		)
		(duplicate_pad_numbers_are_jumpers no)
		(fp_line
			(start -0.69215 -0.2921)
			(end -0.69215 0.2921)
			(stroke
				(width 0.1524)
				(type default)
			)
			(layer "B.SilkS")
		)
		(fp_line
			(start -0.69215 0.2921)
			(end 0.69215 0.2921)
			(stroke
				(width 0.1524)
				(type default)
			)
			(layer "B.SilkS")
		)
		(fp_line
			(start 0.69215 -0.2921)
			(end -0.69215 -0.2921)
			(stroke
				(width 0.1524)
				(type default)
			)
			(layer "B.SilkS")
		)
		(fp_line
			(start 0.69215 0.2921)
			(end 0.69215 -0.2921)
			(stroke
				(width 0.1524)
				(type default)
			)
			(layer "B.SilkS")
		)
		(fp_line
			(start -0.51435 -0.2794)
			(end -0.51435 0.2794)
			(stroke
				(width 0.1)
				(type default)
			)
			(layer "B.Fab")
		)
		(fp_line
			(start -0.51435 0.2794)
			(end 0.51435 0.2794)
			(stroke
				(width 0.1)
				(type default)
			)
			(layer "B.Fab")
		)
		(fp_line
			(start 0.51435 -0.2794)
			(end -0.51435 -0.2794)
			(stroke
				(width 0.1)
				(type default)
			)
			(layer "B.Fab")
		)
		(fp_line
			(start 0.51435 0.2794)
			(end 0.51435 -0.2794)
			(stroke
				(width 0.1)
				(type default)
			)
			(layer "B.Fab")
		)
		(pad "1" smd circle
			(at 0.40005 0 180)
			(size 0 0)
			(layers "B.Cu" "B.Mask" "B.Paste")
			(net "P3V3_AUX_FPGA_VCCIO2")
		)
		(pad "2" smd circle
			(at -0.40005 0 180)
			(size 0 0)
			(layers "B.Cu" "B.Mask" "B.Paste")
			(net "GND")
		)
		(zone
			(layer "B.Cu")
			(hatch none 0.5)
			(connect_pads
				(clearance 0)
			)
			(min_thickness 0.25)
			(keepout
				(tracks not_allowed)
				(vias allowed)
				(pads allowed)
				(copperpour not_allowed)
				(footprints allowed)
			)
			(placement
				(enabled no)
				(sheetname "")
			)
			(fill
				(thermal_gap 0.5)
				(thermal_bridge_width 0.5)
				(island_removal_mode 0)
			)
			(polygon
				(pts
					(xy 181.946042 -115.287806) (xy 181.854602 -115.22964) (xy 181.655212 -115.22964) (xy 181.565042 -115.287806)
					(xy 181.565042 -115.463066) (xy 181.655212 -115.521486) (xy 181.854602 -115.521486) (xy 181.946042 -115.46332)
				)
			)
		)
	)
)
